(kicad_pcb
	(version 20260206)
	(generator "pcbnew")
	(generator_version "10.0")
	(general
		(thickness 1.6)
		(legacy_teardrops no)
	)
	(paper "A4")
	(title_block
		(title "Bryce Canyon_SCC_16316-1_OCP.brd")
		(comment 1 "Bryce Canyon / footprints 1439-1447 of 1561")
	)
	(layers
		(0 "F.Cu" signal "TOP")
		(4 "In1.Cu" signal "L2GND")
		(6 "In2.Cu" signal "L3")
		(8 "In3.Cu" signal "L4VCC")
		(10 "In4.Cu" signal "L5VCC")
		(12 "In5.Cu" signal "L6")
		(14 "In6.Cu" signal "L7GND")
		(2 "B.Cu" signal "BOTTOM")
		(9 "F.Adhes" user "F.Adhesive")
		(11 "B.Adhes" user "B.Adhesive")
		(13 "F.Paste" user "Package Geometry/Pastemask Top")
		(15 "B.Paste" user "Package Geometry/Pastemask Bottom")
		(5 "F.SilkS" user "Ref Des/Silkscreen Top")
		(7 "B.SilkS" user "Ref Des/Silkscreen Bottom")
		(1 "F.Mask" user "Board Geometry/Soldermask Top")
		(3 "B.Mask" user "Board Geometry/Soldermask Bottom")
		(17 "Dwgs.User" user "User.Drawings")
		(19 "Cmts.User" user "User.Comments")
		(21 "Eco1.User" user "User.Eco1")
		(23 "Eco2.User" user "User.Eco2")
		(25 "Edge.Cuts" user "Board Geometry/Outline")
		(27 "Margin" user)
		(31 "F.CrtYd" user "Package Geometry/Place Bound Top")
		(29 "B.CrtYd" user "Package Geometry/Place Bound Bottom")
		(35 "F.Fab" user "Ref Des/Assembly Top")
		(33 "B.Fab" user "Ref Des/Assembly Bottom")
	)
	(footprint ""
		(layer "B.Cu")
		(at 173.7868 -41.86682 -90)
		(property "Reference" "C425"
			(at 0 0 90)
			(layer "B.SilkS")
			(hide yes)
			(effects
				(font
					(size 1.27 1.27)
				)
				(justify mirror)
			)
		)
		(property "Value" "SCD1U6D3V1KX-GP"
			(at 2.8321 -1.7399 270)
			(unlocked yes)
			(layer "B.Fab")
			(hide yes)
			(effects
				(font
					(size 1.016 1.016)
					(thickness 0.1524)
				)
				(justify mirror)
			)
		)
		(property "Device Type" "C0201H13"
			(at 2.8321 -3.2639 270)
			(unlocked yes)
			(layer "B.Fab")
			(hide yes)
			(effects
				(font
					(size 1.016 1.016)
					(thickness 0.1524)
				)
				(justify mirror)
			)
		)
		(duplicate_pad_numbers_are_jumpers no)
		(fp_rect
			(start 0.2794 0.6477)
			(end -0.2794 -0.6477)
			(stroke
				(width 0)
				(type default)
			)
			(fill no)
			(layer "B.CrtYd")
		)
		(fp_rect
			(start 0.2794 0.6477)
			(end -0.2794 -0.6477)
			(stroke
				(width 0)
				(type default)
			)
			(fill no)
			(layer "B.Fab")
		)
		(pad "1" smd custom
			(at 0 -0.2794 90)
			(size 0.0762 0.0762)
			(layers "B.Cu" "B.Mask" "B.Paste")
			(net "P0V975")
			(options
				(clearance outline)
				(anchor circle)
			)
			(primitives
				(gr_poly
					(pts
						(arc
							(start 0.1524 0.127)
							(mid 0.137521 0.162921)
							(end 0.1016 0.1778)
						)
						(arc
							(start -0.1016 0.1778)
							(mid -0.137521 0.162921)
							(end -0.1524 0.127)
						)
						(arc
							(start -0.1524 -0.127)
							(mid -0.137521 -0.162921)
							(end -0.1016 -0.1778)
						)
						(arc
							(start 0.1016 -0.1778)
							(mid 0.137521 -0.162921)
							(end 0.1524 -0.127)
						)
					)
					(width 0)
					(fill yes)
				)
			)
		)
		(pad "2" smd custom
			(at 0 0.2794 90)
			(size 0.0762 0.0762)
			(layers "B.Cu" "B.Mask" "B.Paste")
			(net "GND")
			(options
				(clearance outline)
				(anchor circle)
			)
			(primitives
				(gr_poly
					(pts
						(arc
							(start 0.1524 0.127)
							(mid 0.137521 0.162921)
							(end 0.1016 0.1778)
						)
						(arc
							(start -0.1016 0.1778)
							(mid -0.137521 0.162921)
							(end -0.1524 0.127)
						)
						(arc
							(start -0.1524 -0.127)
							(mid -0.137521 -0.162921)
							(end -0.1016 -0.1778)
						)
						(arc
							(start 0.1016 -0.1778)
							(mid 0.137521 -0.162921)
							(end 0.1524 -0.127)
						)
					)
					(width 0)
					(fill yes)
				)
			)
		)
	)
	(footprint ""
		(layer "B.Cu")
		(at 65.786 -95.4405 90)
		(property "Reference" "C639"
			(at 0 0 90)
			(layer "B.SilkS")
			(hide yes)
			(effects
				(font
					(size 1.27 1.27)
				)
				(justify mirror)
			)
		)
		(property "Value" "SC4D7U25V5KX-1-GP"
			(at 0.0762 -6.1214 90)
			(unlocked yes)
			(layer "B.Fab")
			(hide yes)
			(effects
				(font
					(size 1.016 1.016)
					(thickness 0.1524)
				)
				(justify mirror)
			)
		)
		(property "Device Type" "C805H58"
			(at 0.0762 -8.1534 90)
			(unlocked yes)
			(layer "B.Fab")
			(hide yes)
			(effects
				(font
					(size 1.016 1.016)
					(thickness 0.1524)
				)
				(justify mirror)
			)
		)
		(duplicate_pad_numbers_are_jumpers no)
		(fp_line
			(start -0.635 0)
			(end 0.635 0)
			(stroke
				(width 0.508)
				(type default)
			)
			(layer "B.SilkS")
		)
		(fp_rect
			(start 0.9652 1.778)
			(end -0.9652 -1.778)
			(stroke
				(width 0)
				(type default)
			)
			(fill no)
			(layer "B.CrtYd")
		)
		(fp_poly
			(pts
				(xy 0.9652 -1.778) (xy -0.9652 -1.778) (xy -0.9652 1.778) (xy 0.9652 1.778)
			)
			(stroke
				(width 0)
				(type default)
			)
			(fill no)
			(layer "B.Fab")
		)
		(pad "1" smd rect
			(at 0 -0.9652 270)
			(size 1.397 1.143)
			(layers "B.Cu" "B.Mask" "B.Paste")
			(net "P12V_STBY_VDD_U10")
		)
		(pad "2" smd rect
			(at 0 0.9652 270)
			(size 1.397 1.143)
			(layers "B.Cu" "B.Mask" "B.Paste")
			(net "GND")
		)
	)
	(footprint ""
		(layer "B.Cu")
		(at 172.309028 -32.69869 90)
		(property "Reference" "C380"
			(at 0 0 90)
			(layer "B.SilkS")
			(hide yes)
			(effects
				(font
					(size 1.27 1.27)
				)
				(justify mirror)
			)
		)
		(property "Value" "SCD1U16V2KX-3GP"
			(at -1.1811 -2.7051 90)
			(unlocked yes)
			(layer "B.Fab")
			(hide yes)
			(effects
				(font
					(size 1.016 1.016)
					(thickness 0.1524)
				)
				(justify mirror)
			)
		)
		(property "Device Type" "C402H22"
			(at -1.1811 -4.2291 90)
			(unlocked yes)
			(layer "B.Fab")
			(hide yes)
			(effects
				(font
					(size 1.016 1.016)
					(thickness 0.1524)
				)
				(justify mirror)
			)
		)
		(duplicate_pad_numbers_are_jumpers no)
		(fp_rect
			(start 0.4318 0.9525)
			(end -0.4318 -0.9525)
			(stroke
				(width 0)
				(type default)
			)
			(fill no)
			(layer "B.CrtYd")
		)
		(fp_rect
			(start 0.4318 0.9525)
			(end -0.4318 -0.9525)
			(stroke
				(width 0)
				(type default)
			)
			(fill no)
			(layer "B.Fab")
		)
		(pad "1" smd custom
			(at 0 -0.4445 270)
			(size 0.1524 0.1524)
			(layers "B.Cu" "B.Mask" "B.Paste")
			(net "PCE_VDDH")
			(options
				(clearance outline)
				(anchor circle)
			)
			(primitives
				(gr_poly
					(pts
						(arc
							(start 0.3048 0.2032)
							(mid 0.275042 0.275042)
							(end 0.2032 0.3048)
						)
						(arc
							(start -0.2032 0.3048)
							(mid -0.275042 0.275042)
							(end -0.3048 0.2032)
						)
						(arc
							(start -0.3048 -0.2032)
							(mid -0.275042 -0.275042)
							(end -0.2032 -0.3048)
						)
						(arc
							(start 0.2032 -0.3048)
							(mid 0.275042 -0.275042)
							(end 0.3048 -0.2032)
						)
					)
					(width 0)
					(fill yes)
				)
			)
		)
		(pad "2" smd custom
			(at 0 0.4445 270)
			(size 0.1524 0.1524)
			(layers "B.Cu" "B.Mask" "B.Paste")
			(net "GND")
			(options
				(clearance outline)
				(anchor circle)
			)
			(primitives
				(gr_poly
					(pts
						(arc
							(start 0.3048 0.2032)
							(mid 0.275042 0.275042)
							(end 0.2032 0.3048)
						)
						(arc
							(start -0.2032 0.3048)
							(mid -0.275042 0.275042)
							(end -0.3048 0.2032)
						)
						(arc
							(start -0.3048 -0.2032)
							(mid -0.275042 -0.275042)
							(end -0.2032 -0.3048)
						)
						(arc
							(start 0.2032 -0.3048)
							(mid 0.275042 -0.275042)
							(end 0.3048 -0.2032)
						)
					)
					(width 0)
					(fill yes)
				)
			)
		)
	)
	(footprint ""
		(layer "B.Cu")
		(at 169.632122 -43.47464 180)
		(property "Reference" "C493"
			(at 0 0 0)
			(layer "B.SilkS")
			(hide yes)
			(effects
				(font
					(size 1.27 1.27)
				)
				(justify mirror)
			)
		)
		(property "Value" "SCD1U6D3V1KX-GP"
			(at 2.8321 -1.7399 180)
			(unlocked yes)
			(layer "B.Fab")
			(hide yes)
			(effects
				(font
					(size 1.016 1.016)
					(thickness 0.1524)
				)
				(justify mirror)
			)
		)
		(property "Device Type" "C0201H13"
			(at 2.8321 -3.2639 180)
			(unlocked yes)
			(layer "B.Fab")
			(hide yes)
			(effects
				(font
					(size 1.016 1.016)
					(thickness 0.1524)
				)
				(justify mirror)
			)
		)
		(duplicate_pad_numbers_are_jumpers no)
		(fp_rect
			(start 0.2794 0.6477)
			(end -0.2794 -0.6477)
			(stroke
				(width 0)
				(type default)
			)
			(fill no)
			(layer "B.CrtYd")
		)
		(fp_rect
			(start 0.2794 0.6477)
			(end -0.2794 -0.6477)
			(stroke
				(width 0)
				(type default)
			)
			(fill no)
			(layer "B.Fab")
		)
		(pad "1" smd custom
			(at 0 -0.2794)
			(size 0.0762 0.0762)
			(layers "B.Cu" "B.Mask" "B.Paste")
			(net "P1V8_C")
			(options
				(clearance outline)
				(anchor circle)
			)
			(primitives
				(gr_poly
					(pts
						(arc
							(start 0.1524 0.127)
							(mid 0.137521 0.162921)
							(end 0.1016 0.1778)
						)
						(arc
							(start -0.1016 0.1778)
							(mid -0.137521 0.162921)
							(end -0.1524 0.127)
						)
						(arc
							(start -0.1524 -0.127)
							(mid -0.137521 -0.162921)
							(end -0.1016 -0.1778)
						)
						(arc
							(start 0.1016 -0.1778)
							(mid 0.137521 -0.162921)
							(end 0.1524 -0.127)
						)
					)
					(width 0)
					(fill yes)
				)
			)
		)
		(pad "2" smd custom
			(at 0 0.2794)
			(size 0.0762 0.0762)
			(layers "B.Cu" "B.Mask" "B.Paste")
			(net "GND")
			(options
				(clearance outline)
				(anchor circle)
			)
			(primitives
				(gr_poly
					(pts
						(arc
							(start 0.1524 0.127)
							(mid 0.137521 0.162921)
							(end 0.1016 0.1778)
						)
						(arc
							(start -0.1016 0.1778)
							(mid -0.137521 0.162921)
							(end -0.1524 0.127)
						)
						(arc
							(start -0.1524 -0.127)
							(mid -0.137521 -0.162921)
							(end -0.1016 -0.1778)
						)
						(arc
							(start 0.1016 -0.1778)
							(mid 0.137521 -0.162921)
							(end 0.1524 -0.127)
						)
					)
					(width 0)
					(fill yes)
				)
			)
		)
	)
	(footprint ""
		(layer "B.Cu")
		(at 131.113276 -84.473288)
		(property "Reference" "TP15"
			(at 0 0 0)
			(layer "B.SilkS")
			(hide yes)
			(effects
				(font
					(size 1.27 1.27)
				)
				(justify mirror)
			)
		)
		(property "Value" "TPAD28-2-GP"
			(at 0.0127 -1.6637 0)
			(unlocked yes)
			(layer "B.Fab")
			(hide yes)
			(effects
				(font
					(size 1.016 1.016)
					(thickness 0.1524)
				)
				(justify mirror)
			)
		)
		(property "Device Type" "TPAD28"
			(at 0.0127 -3.1877 0)
			(unlocked yes)
			(layer "B.Fab")
			(hide yes)
			(effects
				(font
					(size 1.016 1.016)
					(thickness 0.1524)
				)
				(justify mirror)
			)
		)
		(duplicate_pad_numbers_are_jumpers no)
		(fp_poly
			(pts
				(arc
					(start 0.3556 0)
					(mid -0.3556 0)
					(end 0.3556 0)
				)
			)
			(stroke
				(width 0)
				(type default)
			)
			(fill no)
			(layer "B.CrtYd")
		)
		(fp_poly
			(pts
				(arc
					(start 0.6096 0)
					(mid -0.6096 0)
					(end 0.6096 0)
				)
			)
			(stroke
				(width 0)
				(type default)
			)
			(fill no)
			(layer "B.Fab")
		)
		(pad "1" smd circle
			(at 0 0 180)
			(size 0.7112 0.7112)
			(layers "B.Cu" "B.Mask" "B.Paste")
			(net "EXP_I2C_SDA11")
		)
	)
	(footprint ""
		(layer "B.Cu")
		(at 120.4976 -70.739 -90)
		(property "Reference" "C214"
			(at 0 0 90)
			(layer "B.SilkS")
			(hide yes)
			(effects
				(font
					(size 1.27 1.27)
				)
				(justify mirror)
			)
		)
		(property "Value" "SC1U16V2KX-7-GP"
			(at -1.7526 -1.6002 270)
			(unlocked yes)
			(layer "B.Fab")
			(hide yes)
			(effects
				(font
					(size 1.016 1.016)
					(thickness 0.1524)
				)
				(justify mirror)
			)
		)
		(property "Device Type" "C402-TO0D2H24"
			(at -1.7526 -3.1242 270)
			(unlocked yes)
			(layer "B.Fab")
			(hide yes)
			(effects
				(font
					(size 1.016 1.016)
					(thickness 0.1524)
				)
				(justify mirror)
			)
		)
		(duplicate_pad_numbers_are_jumpers no)
		(fp_rect
			(start 0.4826 0.889)
			(end -0.4826 -0.889)
			(stroke
				(width 0)
				(type default)
			)
			(fill no)
			(layer "B.CrtYd")
		)
		(fp_rect
			(start 0.4826 0.889)
			(end -0.4826 -0.889)
			(stroke
				(width 0)
				(type default)
			)
			(fill no)
			(layer "B.Fab")
		)
		(pad "1" smd custom
			(at 0 -0.4572 90)
			(size 0.1524 0.1524)
			(layers "B.Cu" "B.Mask" "B.Paste")
			(net "GB_VDDH")
			(options
				(clearance outline)
				(anchor circle)
			)
			(primitives
				(gr_poly
					(pts
						(arc
							(start -0.254 -0.3048)
							(mid -0.325842 -0.275042)
							(end -0.3556 -0.2032)
						)
						(arc
							(start -0.3556 0.2032)
							(mid -0.325842 0.275042)
							(end -0.254 0.3048)
						)
						(arc
							(start 0.254 0.3048)
							(mid 0.325842 0.275042)
							(end 0.3556 0.2032)
						)
						(arc
							(start 0.3556 -0.2032)
							(mid 0.325842 -0.275042)
							(end 0.254 -0.3048)
						)
					)
					(width 0)
					(fill yes)
				)
			)
		)
		(pad "2" smd custom
			(at 0 0.4572 90)
			(size 0.1524 0.1524)
			(layers "B.Cu" "B.Mask" "B.Paste")
			(net "GND")
			(options
				(clearance outline)
				(anchor circle)
			)
			(primitives
				(gr_poly
					(pts
						(arc
							(start -0.254 -0.3048)
							(mid -0.325842 -0.275042)
							(end -0.3556 -0.2032)
						)
						(arc
							(start -0.3556 0.2032)
							(mid -0.325842 0.275042)
							(end -0.254 0.3048)
						)
						(arc
							(start 0.254 0.3048)
							(mid 0.325842 0.275042)
							(end 0.3556 0.2032)
						)
						(arc
							(start 0.3556 -0.2032)
							(mid 0.325842 -0.275042)
							(end 0.254 -0.3048)
						)
					)
					(width 0)
					(fill yes)
				)
			)
		)
	)
	(footprint ""
		(layer "B.Cu")
		(at 184.465468 -38.39845 90)
		(property "Reference" "C490"
			(at 0 0 90)
			(layer "B.SilkS")
			(hide yes)
			(effects
				(font
					(size 1.27 1.27)
				)
				(justify mirror)
			)
		)
		(property "Value" "SCD1U6D3V1KX-GP"
			(at 2.8321 -1.7399 90)
			(unlocked yes)
			(layer "B.Fab")
			(hide yes)
			(effects
				(font
					(size 1.016 1.016)
					(thickness 0.1524)
				)
				(justify mirror)
			)
		)
		(property "Device Type" "C0201H13"
			(at 2.8321 -3.2639 90)
			(unlocked yes)
			(layer "B.Fab")
			(hide yes)
			(effects
				(font
					(size 1.016 1.016)
					(thickness 0.1524)
				)
				(justify mirror)
			)
		)
		(duplicate_pad_numbers_are_jumpers no)
		(fp_rect
			(start 0.2794 0.6477)
			(end -0.2794 -0.6477)
			(stroke
				(width 0)
				(type default)
			)
			(fill no)
			(layer "B.CrtYd")
		)
		(fp_rect
			(start 0.2794 0.6477)
			(end -0.2794 -0.6477)
			(stroke
				(width 0)
				(type default)
			)
			(fill no)
			(layer "B.Fab")
		)
		(pad "1" smd custom
			(at 0 -0.2794 270)
			(size 0.0762 0.0762)
			(layers "B.Cu" "B.Mask" "B.Paste")
			(net "P1V8_C")
			(options
				(clearance outline)
				(anchor circle)
			)
			(primitives
				(gr_poly
					(pts
						(arc
							(start 0.1524 0.127)
							(mid 0.137521 0.162921)
							(end 0.1016 0.1778)
						)
						(arc
							(start -0.1016 0.1778)
							(mid -0.137521 0.162921)
							(end -0.1524 0.127)
						)
						(arc
							(start -0.1524 -0.127)
							(mid -0.137521 -0.162921)
							(end -0.1016 -0.1778)
						)
						(arc
							(start 0.1016 -0.1778)
							(mid 0.137521 -0.162921)
							(end 0.1524 -0.127)
						)
					)
					(width 0)
					(fill yes)
				)
			)
		)
		(pad "2" smd custom
			(at 0 0.2794 270)
			(size 0.0762 0.0762)
			(layers "B.Cu" "B.Mask" "B.Paste")
			(net "GND")
			(options
				(clearance outline)
				(anchor circle)
			)
			(primitives
				(gr_poly
					(pts
						(arc
							(start 0.1524 0.127)
							(mid 0.137521 0.162921)
							(end 0.1016 0.1778)
						)
						(arc
							(start -0.1016 0.1778)
							(mid -0.137521 0.162921)
							(end -0.1524 0.127)
						)
						(arc
							(start -0.1524 -0.127)
							(mid -0.137521 -0.162921)
							(end -0.1016 -0.1778)
						)
						(arc
							(start 0.1016 -0.1778)
							(mid 0.137521 -0.162921)
							(end 0.1524 -0.127)
						)
					)
					(width 0)
					(fill yes)
				)
			)
		)
	)
	(footprint ""
		(layer "B.Cu")
		(at 140.716 -88.9)
		(property "Reference" "R66"
			(at 0 0 0)
			(layer "B.SilkS")
			(hide yes)
			(effects
				(font
					(size 1.27 1.27)
				)
				(justify mirror)
			)
		)
		(property "Value" "1KR2F-3-GP"
			(at -0.064008 -3.993896 0)
			(unlocked yes)
			(layer "B.Fab")
			(hide yes)
			(effects
				(font
					(size 1.016 1.016)
					(thickness 0.1524)
				)
				(justify mirror)
			)
		)
		(property "Device Type" "R402H16"
			(at -0.064008 -5.517896 0)
			(unlocked yes)
			(layer "B.Fab")
			(hide yes)
			(effects
				(font
					(size 1.016 1.016)
					(thickness 0.1524)
				)
				(justify mirror)
			)
		)
		(duplicate_pad_numbers_are_jumpers no)
		(fp_line
			(start -0.508 -0.9398)
			(end 0.508 -0.9398)
			(stroke
				(width 0.1524)
				(type default)
			)
			(layer "B.SilkS")
		)
		(fp_line
			(start 0.508 -0.9398)
			(end 0.508 0.9398)
			(stroke
				(width 0.1524)
				(type default)
			)
			(layer "B.SilkS")
		)
		(fp_rect
			(start 0.508 0.9398)
			(end -0.508 -0.9398)
			(stroke
				(width 0)
				(type default)
			)
			(fill no)
			(layer "B.CrtYd")
		)
		(fp_rect
			(start 0.508 0.9398)
			(end -0.508 -0.9398)
			(stroke
				(width 0)
				(type default)
			)
			(fill no)
			(layer "B.Fab")
		)
		(pad "1" smd custom
			(at 0 -0.4445 180)
			(size 0.1397 0.1397)
			(layers "B.Cu" "B.Mask" "B.Paste")
			(net "P1V8_E")
			(options
				(clearance outline)
				(anchor circle)
			)
			(primitives
				(gr_poly
					(pts
						(arc
							(start -0.1778 0.2794)
							(mid -0.249642 0.249642)
							(end -0.2794 0.1778)
						)
						(arc
							(start -0.2794 -0.1778)
							(mid -0.249642 -0.249642)
							(end -0.1778 -0.2794)
						)
						(arc
							(start 0.1778 -0.2794)
							(mid 0.249642 -0.249642)
							(end 0.2794 -0.1778)
						)
						(arc
							(start 0.2794 0.1778)
							(mid 0.249642 0.249642)
							(end 0.1778 0.2794)
						)
					)
					(width 0)
					(fill yes)
				)
			)
		)
		(pad "2" smd custom
			(at 0 0.4445 180)
			(size 0.1397 0.1397)
			(layers "B.Cu" "B.Mask" "B.Paste")
			(net "EXP_I2C_SCL9")
			(options
				(clearance outline)
				(anchor circle)
			)
			(primitives
				(gr_poly
					(pts
						(arc
							(start -0.1778 0.2794)
							(mid -0.249642 0.249642)
							(end -0.2794 0.1778)
						)
						(arc
							(start -0.2794 -0.1778)
							(mid -0.249642 -0.249642)
							(end -0.1778 -0.2794)
						)
						(arc
							(start 0.1778 -0.2794)
							(mid 0.249642 -0.249642)
							(end 0.2794 -0.1778)
						)
						(arc
							(start 0.2794 0.1778)
							(mid 0.249642 0.249642)
							(end 0.1778 0.2794)
						)
					)
					(width 0)
					(fill yes)
				)
			)
		)
	)
	(footprint ""
		(layer "B.Cu")
		(at 129.397252 -58.696606 90)
		(property "Reference" "C271"
			(at 0 0 90)
			(layer "B.SilkS")
			(hide yes)
			(effects
				(font
					(size 1.27 1.27)
				)
				(justify mirror)
			)
		)
		(property "Value" "SCD1U6D3V1KX-GP"
			(at 2.8321 -1.7399 90)
			(unlocked yes)
			(layer "B.Fab")
			(hide yes)
			(effects
				(font
					(size 1.016 1.016)
					(thickness 0.1524)
				)
				(justify mirror)
			)
		)
		(property "Device Type" "C0201H13"
			(at 2.8321 -3.2639 90)
			(unlocked yes)
			(layer "B.Fab")
			(hide yes)
			(effects
				(font
					(size 1.016 1.016)
					(thickness 0.1524)
				)
				(justify mirror)
			)
		)
		(duplicate_pad_numbers_are_jumpers no)
		(fp_rect
			(start 0.2794 0.6477)
			(end -0.2794 -0.6477)
			(stroke
				(width 0)
				(type default)
			)
			(fill no)
			(layer "B.CrtYd")
		)
		(fp_rect
			(start 0.2794 0.6477)
			(end -0.2794 -0.6477)
			(stroke
				(width 0)
				(type default)
			)
			(fill no)
			(layer "B.Fab")
		)
		(pad "1" smd custom
			(at 0 -0.2794 270)
			(size 0.0762 0.0762)
			(layers "B.Cu" "B.Mask" "B.Paste")
			(net "GB_VDDA")
			(options
				(clearance outline)
				(anchor circle)
			)
			(primitives
				(gr_poly
					(pts
						(arc
							(start 0.1524 0.127)
							(mid 0.137521 0.162921)
							(end 0.1016 0.1778)
						)
						(arc
							(start -0.1016 0.1778)
							(mid -0.137521 0.162921)
							(end -0.1524 0.127)
						)
						(arc
							(start -0.1524 -0.127)
							(mid -0.137521 -0.162921)
							(end -0.1016 -0.1778)
						)
						(arc
							(start 0.1016 -0.1778)
							(mid 0.137521 -0.162921)
							(end 0.1524 -0.127)
						)
					)
					(width 0)
					(fill yes)
				)
			)
		)
		(pad "2" smd custom
			(at 0 0.2794 270)
			(size 0.0762 0.0762)
			(layers "B.Cu" "B.Mask" "B.Paste")
			(net "GND")
			(options
				(clearance outline)
				(anchor circle)
			)
			(primitives
				(gr_poly
					(pts
						(arc
							(start 0.1524 0.127)
							(mid 0.137521 0.162921)
							(end 0.1016 0.1778)
						)
						(arc
							(start -0.1016 0.1778)
							(mid -0.137521 0.162921)
							(end -0.1524 0.127)
						)
						(arc
							(start -0.1524 -0.127)
							(mid -0.137521 -0.162921)
							(end -0.1016 -0.1778)
						)
						(arc
							(start 0.1016 -0.1778)
							(mid 0.137521 -0.162921)
							(end 0.1524 -0.127)
						)
					)
					(width 0)
					(fill yes)
				)
			)
		)
	)
)
